(kicad_pcb
	(version 20241229)
	(generator "pcbnew")
	(generator_version "9.0")
	(general
		(thickness 1.59)
		(legacy_teardrops no)
	)
	(paper "A3")
	(title_block
		(title "usb-c-power-adapter")
		(date "2025-06-24")
		(rev "1.1.2")
		(company "Antmicro")
		(comment 9 "footprints 99-103 of 122")
	)
	(layers
		(0 "F.Cu" signal)
		(4 "In1.Cu" signal)
		(6 "In2.Cu" signal)
		(2 "B.Cu" signal)
		(9 "F.Adhes" user "F.Adhesive")
		(11 "B.Adhes" user "B.Adhesive")
		(13 "F.Paste" user)
		(15 "B.Paste" user)
		(5 "F.SilkS" user "F.Silkscreen")
		(7 "B.SilkS" user "B.Silkscreen")
		(1 "F.Mask" user)
		(3 "B.Mask" user)
		(17 "Dwgs.User" user "User.Drawings")
		(19 "Cmts.User" user "User.Comments")
		(21 "Eco1.User" user "User.Eco1")
		(23 "Eco2.User" user "User.Eco2")
		(25 "Edge.Cuts" user)
		(27 "Margin" user)
		(31 "F.CrtYd" user "F.Courtyard")
		(29 "B.CrtYd" user "B.Courtyard")
		(35 "F.Fab" user)
		(33 "B.Fab" user)
	)
	(footprint "antmicro-footprints:C_0402_1005Metric"
		(layer "B.Cu")
		(at 91.851 68.6 180)
		(descr "Capacitor SMD 0402")
		(tags "capacitor SMD 0402")
		(property "Reference" "C27"
			(at 0.825 -0.45 0)
			(layer "B.SilkS")
			(effects
				(font
					(size 0.7 0.7)
					(thickness 0.15)
				)
				(justify left bottom mirror)
			)
		)
		(property "Value" "C_4u7_25V_0402"
			(at -1.022927 -2.155213 0)
			(layer "B.Fab")
			(effects
				(font
					(size 0.7 0.7)
					(thickness 0.15)
				)
				(justify left bottom mirror)
			)
		)
		(property "Datasheet" "https://www.murata.com/products/productdetail?partno=GRM155C61E475ME15%23"
			(at 0 0 180)
			(layer "F.Fab")
			(hide yes)
			(effects
				(font
					(size 1.27 1.27)
					(thickness 0.15)
				)
			)
		)
		(property "Description" "SMD Multilayer Ceramic Capacitor"
			(at 0 0 180)
			(layer "F.Fab")
			(hide yes)
			(effects
				(font
					(size 1.27 1.27)
					(thickness 0.15)
				)
			)
		)
		(property "MPN" "GRM155C61E475ME15J"
			(at 0 0 180)
			(unlocked yes)
			(layer "B.Fab")
			(hide yes)
			(effects
				(font
					(size 1 1)
					(thickness 0.15)
				)
				(justify mirror)
			)
		)
		(property "Manufacturer" "Murata"
			(at 0 0 180)
			(unlocked yes)
			(layer "B.Fab")
			(hide yes)
			(effects
				(font
					(size 1 1)
					(thickness 0.15)
				)
				(justify mirror)
			)
		)
		(property "License" "Apache-2.0"
			(at 0 0 180)
			(unlocked yes)
			(layer "B.Fab")
			(hide yes)
			(effects
				(font
					(size 1 1)
					(thickness 0.15)
				)
				(justify mirror)
			)
		)
		(property "Author" "Antmicro"
			(at 0 0 180)
			(unlocked yes)
			(layer "B.Fab")
			(hide yes)
			(effects
				(font
					(size 1 1)
					(thickness 0.15)
				)
				(justify mirror)
			)
		)
		(property "Val" "4u7"
			(at 0 0 180)
			(unlocked yes)
			(layer "B.Fab")
			(hide yes)
			(effects
				(font
					(size 1 1)
					(thickness 0.15)
				)
				(justify mirror)
			)
		)
		(property "Voltage" "25V"
			(at 0 0 180)
			(unlocked yes)
			(layer "B.Fab")
			(hide yes)
			(effects
				(font
					(size 1 1)
					(thickness 0.15)
				)
				(justify mirror)
			)
		)
		(property "Dielectric" "X5S"
			(at 0 0 180)
			(unlocked yes)
			(layer "B.Fab")
			(hide yes)
			(effects
				(font
					(size 1 1)
					(thickness 0.15)
				)
				(justify mirror)
			)
		)
		(sheetname "/USB PD/")
		(sheetfile "usb_pd.kicad_sch")
		(attr smd)
		(fp_rect
			(start -0.925 0.47)
			(end 0.925 -0.47)
			(stroke
				(width 0.05)
				(type default)
			)
			(fill no)
			(layer "B.CrtYd")
		)
		(fp_line
			(start 0.504 0.25)
			(end -0.494 0.25)
			(stroke
				(width 0.15)
				(type solid)
			)
			(layer "B.Fab")
		)
		(fp_line
			(start 0.504 -0.248)
			(end 0.504 0.25)
			(stroke
				(width 0.15)
				(type solid)
			)
			(layer "B.Fab")
		)
		(fp_line
			(start -0.494 0.25)
			(end -0.494 -0.248)
			(stroke
				(width 0.15)
				(type solid)
			)
			(layer "B.Fab")
		)
		(fp_line
			(start -0.494 -0.248)
			(end 0.504 -0.248)
			(stroke
				(width 0.15)
				(type solid)
			)
			(layer "B.Fab")
		)
		(pad "1" smd roundrect
			(at -0.48 0 180)
			(size 0.59 0.64)
			(layers "B.Cu" "B.Mask" "B.Paste")
			(roundrect_rratio 0.25)
			(net 2 "GND")
			(pintype "passive")
		)
		(pad "2" smd roundrect
			(at 0.48 0 180)
			(size 0.59 0.64)
			(layers "B.Cu" "B.Mask" "B.Paste")
			(roundrect_rratio 0.25)
			(net 6 "VBUS")
			(pintype "passive")
		)
	)
	(footprint "antmicro-footprints:R_0402_1005Metric"
		(layer "B.Cu")
		(at 88.576 89.1 -90)
		(descr "Resistor SMD 0402")
		(tags "resistor SMD 0402")
		(property "Reference" "R41"
			(at -0.85 -2.7 90)
			(layer "B.SilkS")
			(effects
				(font
					(size 0.7 0.7)
					(thickness 0.15)
				)
				(justify left bottom mirror)
			)
		)
		(property "Value" "R_1k_0402"
			(at -1.011843 -1.772047 90)
			(layer "B.Fab")
			(effects
				(font
					(size 0.7 0.7)
					(thickness 0.15)
				)
				(justify left bottom mirror)
			)
		)
		(property "Datasheet" "https://www.bourns.com/docs/product-datasheets/cr.pdf"
			(at 0 0 270)
			(layer "F.Fab")
			(hide yes)
			(effects
				(font
					(size 1.27 1.27)
					(thickness 0.15)
				)
			)
		)
		(property "Description" "SMD Chip Resistor, 1 kohm, ± 1%, 63 mW, 0402 [1005 Metric], Thick Film, General Purpose"
			(at 0 0 270)
			(layer "F.Fab")
			(hide yes)
			(effects
				(font
					(size 1.27 1.27)
					(thickness 0.15)
				)
			)
		)
		(property "MPN" "CR0402-FX-1001GLF"
			(at 0 0 270)
			(unlocked yes)
			(layer "B.Fab")
			(hide yes)
			(effects
				(font
					(size 1 1)
					(thickness 0.15)
				)
				(justify mirror)
			)
		)
		(property "Manufacturer" "Bourns"
			(at 0 0 270)
			(unlocked yes)
			(layer "B.Fab")
			(hide yes)
			(effects
				(font
					(size 1 1)
					(thickness 0.15)
				)
				(justify mirror)
			)
		)
		(property "License" "Apache-2.0"
			(at 0 0 270)
			(unlocked yes)
			(layer "B.Fab")
			(hide yes)
			(effects
				(font
					(size 1 1)
					(thickness 0.15)
				)
				(justify mirror)
			)
		)
		(property "Author" "Antmicro"
			(at 0 0 270)
			(unlocked yes)
			(layer "B.Fab")
			(hide yes)
			(effects
				(font
					(size 1 1)
					(thickness 0.15)
				)
				(justify mirror)
			)
		)
		(property "Val" "1k"
			(at 0 0 270)
			(unlocked yes)
			(layer "B.Fab")
			(hide yes)
			(effects
				(font
					(size 1 1)
					(thickness 0.15)
				)
				(justify mirror)
			)
		)
		(property "Tolerance" "1%"
			(at 0 0 270)
			(unlocked yes)
			(layer "B.Fab")
			(hide yes)
			(effects
				(font
					(size 1 1)
					(thickness 0.15)
				)
				(justify mirror)
			)
		)
		(sheetname "/DC-DC Converters/")
		(sheetfile "dc-dc_converters.kicad_sch")
		(attr smd)
		(fp_rect
			(start -0.925 0.47)
			(end 0.925 -0.47)
			(stroke
				(width 0.05)
				(type default)
			)
			(fill no)
			(layer "B.CrtYd")
		)
		(fp_rect
			(start -0.5 0.25)
			(end 0.5 -0.25)
			(stroke
				(width 0.15)
				(type solid)
			)
			(fill no)
			(layer "B.Fab")
		)
		(pad "1" smd roundrect
			(at -0.48 0 270)
			(size 0.59 0.64)
			(layers "B.Cu" "B.Mask" "B.Paste")
			(roundrect_rratio 0.25)
			(net 2 "GND")
			(pintype "passive")
		)
		(pad "2" smd roundrect
			(at 0.48 0 270)
			(size 0.59 0.64)
			(layers "B.Cu" "B.Mask" "B.Paste")
			(roundrect_rratio 0.25)
			(net 40 "Net-(U3-FB)")
			(pintype "passive")
		)
	)
	(footprint "antmicro-footprints:C_0603_1608Metric"
		(layer "B.Cu")
		(at 83.276 88.475 180)
		(descr "Capacitor SMD 0603")
		(tags "capacitor 0603")
		(property "Reference" "C25"
			(at -1.524 -1.525 180)
			(layer "B.SilkS")
			(effects
				(font
					(size 0.7 0.7)
					(thickness 0.15)
				)
				(justify left bottom mirror)
			)
		)
		(property "Value" "C_10u_25V_0603"
			(at -1.42757 -1.770288 0)
			(layer "B.Fab")
			(effects
				(font
					(size 0.7 0.7)
					(thickness 0.15)
				)
				(justify left bottom mirror)
			)
		)
		(property "Datasheet" "https://product.tdk.com/en/search/capacitor/ceramic/mlcc/info?part_no=C1608X5R1E106M080AC"
			(at 0 0 180)
			(layer "F.Fab")
			(hide yes)
			(effects
				(font
					(size 1.27 1.27)
					(thickness 0.15)
				)
			)
		)
		(property "Description" "SMD Multilayer Ceramic Capacitor, 10 µF, 25 V, 0603 [1608 Metric], ± 20%, X5R, C"
			(at 0 0 180)
			(layer "F.Fab")
			(hide yes)
			(effects
				(font
					(size 1.27 1.27)
					(thickness 0.15)
				)
			)
		)
		(property "MPN" "C1608X5R1E106M080AC"
			(at 0 0 180)
			(unlocked yes)
			(layer "B.Fab")
			(hide yes)
			(effects
				(font
					(size 1 1)
					(thickness 0.15)
				)
				(justify mirror)
			)
		)
		(property "Manufacturer" "TDK"
			(at 0 0 180)
			(unlocked yes)
			(layer "B.Fab")
			(hide yes)
			(effects
				(font
					(size 1 1)
					(thickness 0.15)
				)
				(justify mirror)
			)
		)
		(property "License" "Apache-2.0"
			(at 0 0 180)
			(unlocked yes)
			(layer "B.Fab")
			(hide yes)
			(effects
				(font
					(size 1 1)
					(thickness 0.15)
				)
				(justify mirror)
			)
		)
		(property "Author" "Antmicro"
			(at 0 0 180)
			(unlocked yes)
			(layer "B.Fab")
			(hide yes)
			(effects
				(font
					(size 1 1)
					(thickness 0.15)
				)
				(justify mirror)
			)
		)
		(property "Val" "10u"
			(at 0 0 180)
			(unlocked yes)
			(layer "B.Fab")
			(hide yes)
			(effects
				(font
					(size 1 1)
					(thickness 0.15)
				)
				(justify mirror)
			)
		)
		(property "Voltage" "25V"
			(at 0 0 180)
			(unlocked yes)
			(layer "B.Fab")
			(hide yes)
			(effects
				(font
					(size 1 1)
					(thickness 0.15)
				)
				(justify mirror)
			)
		)
		(property "Dielectric" ""
			(at 0 0 180)
			(unlocked yes)
			(layer "B.Fab")
			(hide yes)
			(effects
				(font
					(size 1 1)
					(thickness 0.15)
				)
				(justify mirror)
			)
		)
		(sheetname "/DC-DC Converters/")
		(sheetfile "dc-dc_converters.kicad_sch")
		(attr smd)
		(fp_line
			(start 0.15 0.4)
			(end -0.15 0.4)
			(stroke
				(width 0.15)
				(type solid)
			)
			(layer "B.SilkS")
		)
		(fp_line
			(start 0.15 -0.4)
			(end -0.15 -0.4)
			(stroke
				(width 0.15)
				(type solid)
			)
			(layer "B.SilkS")
		)
		(fp_rect
			(start -1.25 0.65)
			(end 1.25 -0.65)
			(stroke
				(width 0.05)
				(type solid)
			)
			(fill no)
			(layer "B.CrtYd")
		)
		(fp_rect
			(start -0.8 0.4)
			(end 0.8 -0.4)
			(stroke
				(width 0.15)
				(type solid)
			)
			(fill no)
			(layer "B.Fab")
		)
		(pad "1" smd roundrect
			(at -0.7 0 180)
			(size 0.8 1)
			(layers "B.Cu" "B.Mask" "B.Paste")
			(roundrect_rratio 0.2)
			(net 2 "GND")
			(pintype "passive")
		)
		(pad "2" smd roundrect
			(at 0.7 0 180)
			(size 0.8 1)
			(layers "B.Cu" "B.Mask" "B.Paste")
			(roundrect_rratio 0.2)
			(net 25 "+5V")
			(pintype "passive")
		)
	)
	(footprint "antmicro-footprints:C_0805_2012Metric"
		(layer "B.Cu")
		(at 99.8 93.75 -90)
		(descr "Capacitor SMD 0805")
		(tags "capacitor SMD 0805")
		(property "Reference" "C18"
			(at -1.04 0.867 90)
			(layer "B.SilkS")
			(effects
				(font
					(size 0.7 0.7)
					(thickness 0.15)
				)
				(justify left bottom mirror)
			)
		)
		(property "Value" "C_22u_25V_0805"
			(at -2.055717 -1.963152 90)
			(layer "B.Fab")
			(effects
				(font
					(size 0.7 0.7)
					(thickness 0.15)
				)
				(justify left bottom mirror)
			)
		)
		(property "Datasheet" "https://product.samsungsem.com/mlcc/CL21A226MAYNNN.do"
			(at 0 0 270)
			(layer "F.Fab")
			(hide yes)
			(effects
				(font
					(size 1.27 1.27)
					(thickness 0.15)
				)
			)
		)
		(property "Description" "SMT Multilayer Ceramic Capacitor, 22uF, +/-20%, 25V, X5R, 0805 [2012 Metric]"
			(at 0 0 270)
			(layer "F.Fab")
			(hide yes)
			(effects
				(font
					(size 1.27 1.27)
					(thickness 0.15)
				)
			)
		)
		(property "MPN" "CL21A226MAYNNNE"
			(at 0 0 270)
			(unlocked yes)
			(layer "B.Fab")
			(hide yes)
			(effects
				(font
					(size 1 1)
					(thickness 0.15)
				)
				(justify mirror)
			)
		)
		(property "Manufacturer" "Samsung Electro-Mechanics"
			(at 0 0 270)
			(unlocked yes)
			(layer "B.Fab")
			(hide yes)
			(effects
				(font
					(size 1 1)
					(thickness 0.15)
				)
				(justify mirror)
			)
		)
		(property "License" "Apache-2.0"
			(at 0 0 270)
			(unlocked yes)
			(layer "B.Fab")
			(hide yes)
			(effects
				(font
					(size 1 1)
					(thickness 0.15)
				)
				(justify mirror)
			)
		)
		(property "Author" "Antmicro"
			(at 0 0 270)
			(unlocked yes)
			(layer "B.Fab")
			(hide yes)
			(effects
				(font
					(size 1 1)
					(thickness 0.15)
				)
				(justify mirror)
			)
		)
		(property "Val" "22u"
			(at 0 0 270)
			(unlocked yes)
			(layer "B.Fab")
			(hide yes)
			(effects
				(font
					(size 1 1)
					(thickness 0.15)
				)
				(justify mirror)
			)
		)
		(property "Voltage" "25V"
			(at 0 0 270)
			(unlocked yes)
			(layer "B.Fab")
			(hide yes)
			(effects
				(font
					(size 1 1)
					(thickness 0.15)
				)
				(justify mirror)
			)
		)
		(property "Dielectric" "X5R"
			(at 0 0 270)
			(unlocked yes)
			(layer "B.Fab")
			(hide yes)
			(effects
				(font
					(size 1 1)
					(thickness 0.15)
				)
				(justify mirror)
			)
		)
		(property "Public" "False"
			(at 0 0 270)
			(unlocked yes)
			(layer "B.Fab")
			(hide yes)
			(effects
				(font
					(size 1 1)
					(thickness 0.15)
				)
				(justify mirror)
			)
		)
		(sheetname "/DC-DC Converters/")
		(sheetfile "dc-dc_converters.kicad_sch")
		(attr smd)
		(fp_line
			(start 0.3 0.7)
			(end -0.3 0.7)
			(stroke
				(width 0.15)
				(type solid)
			)
			(layer "B.SilkS")
		)
		(fp_line
			(start 0.3 -0.7)
			(end -0.3 -0.7)
			(stroke
				(width 0.15)
				(type solid)
			)
			(layer "B.SilkS")
		)
		(fp_rect
			(start 1.95 0.9)
			(end -1.95 -0.9)
			(stroke
				(width 0.05)
				(type default)
			)
			(fill no)
			(layer "B.CrtYd")
		)
		(fp_rect
			(start -0.95 0.675)
			(end 0.95 -0.675)
			(stroke
				(width 0.15)
				(type solid)
			)
			(fill no)
			(layer "B.Fab")
		)
		(pad "1" smd roundrect
			(at -1.1 0 270)
			(size 1.2 1.3)
			(layers "B.Cu" "B.Mask" "B.Paste")
			(roundrect_rratio 0.25)
			(net 2 "GND")
			(pintype "passive")
		)
		(pad "2" smd roundrect
			(at 1.1 0 270)
			(size 1.2 1.3)
			(layers "B.Cu" "B.Mask" "B.Paste")
			(roundrect_rratio 0.25)
			(net 5 "+12V")
			(pintype "passive")
		)
	)
	(footprint "antmicro-footprints:C_0805_2012Metric"
		(layer "B.Cu")
		(at 97.95 98.2 90)
		(descr "Capacitor SMD 0805")
		(tags "capacitor SMD 0805")
		(property "Reference" "C39"
			(at 1.807 -0.922 180)
			(layer "B.SilkS")
			(effects
				(font
					(size 0.7 0.7)
					(thickness 0.15)
				)
				(justify right bottom mirror)
			)
		)
		(property "Value" "C_22u_25V_0805"
			(at -2.055717 -1.963152 90)
			(layer "B.Fab")
			(effects
				(font
					(size 0.7 0.7)
					(thickness 0.15)
				)
				(justify right bottom mirror)
			)
		)
		(property "Datasheet" "https://product.samsungsem.com/mlcc/CL21A226MAYNNN.do"
			(at 0 0 90)
			(layer "F.Fab")
			(hide yes)
			(effects
				(font
					(size 1.27 1.27)
					(thickness 0.15)
				)
			)
		)
		(property "Description" "SMT Multilayer Ceramic Capacitor, 22uF, +/-20%, 25V, X5R, 0805 [2012 Metric]"
			(at 0 0 90)
			(layer "F.Fab")
			(hide yes)
			(effects
				(font
					(size 1.27 1.27)
					(thickness 0.15)
				)
			)
		)
		(property "MPN" "CL21A226MAYNNNE"
			(at 0 0 90)
			(unlocked yes)
			(layer "B.Fab")
			(hide yes)
			(effects
				(font
					(size 1 1)
					(thickness 0.15)
				)
				(justify mirror)
			)
		)
		(property "Manufacturer" "Samsung Electro-Mechanics"
			(at 0 0 90)
			(unlocked yes)
			(layer "B.Fab")
			(hide yes)
			(effects
				(font
					(size 1 1)
					(thickness 0.15)
				)
				(justify mirror)
			)
		)
		(property "License" "Apache-2.0"
			(at 0 0 90)
			(unlocked yes)
			(layer "B.Fab")
			(hide yes)
			(effects
				(font
					(size 1 1)
					(thickness 0.15)
				)
				(justify mirror)
			)
		)
		(property "Author" "Antmicro"
			(at 0 0 90)
			(unlocked yes)
			(layer "B.Fab")
			(hide yes)
			(effects
				(font
					(size 1 1)
					(thickness 0.15)
				)
				(justify mirror)
			)
		)
		(property "Val" "22u"
			(at 0 0 90)
			(unlocked yes)
			(layer "B.Fab")
			(hide yes)
			(effects
				(font
					(size 1 1)
					(thickness 0.15)
				)
				(justify mirror)
			)
		)
		(property "Voltage" "25V"
			(at 0 0 90)
			(unlocked yes)
			(layer "B.Fab")
			(hide yes)
			(effects
				(font
					(size 1 1)
					(thickness 0.15)
				)
				(justify mirror)
			)
		)
		(property "Dielectric" "X5R"
			(at 0 0 90)
			(unlocked yes)
			(layer "B.Fab")
			(hide yes)
			(effects
				(font
					(size 1 1)
					(thickness 0.15)
				)
				(justify mirror)
			)
		)
		(property "Public" "False"
			(at 0 0 90)
			(unlocked yes)
			(layer "B.Fab")
			(hide yes)
			(effects
				(font
					(size 1 1)
					(thickness 0.15)
				)
				(justify mirror)
			)
		)
		(sheetname "/DC-DC Converters/")
		(sheetfile "dc-dc_converters.kicad_sch")
		(attr smd)
		(fp_line
			(start 0.3 -0.7)
			(end -0.3 -0.7)
			(stroke
				(width 0.15)
				(type solid)
			)
			(layer "B.SilkS")
		)
		(fp_line
			(start 0.3 0.7)
			(end -0.3 0.7)
			(stroke
				(width 0.15)
				(type solid)
			)
			(layer "B.SilkS")
		)
		(fp_rect
			(start 1.95 0.9)
			(end -1.95 -0.9)
			(stroke
				(width 0.05)
				(type default)
			)
			(fill no)
			(layer "B.CrtYd")
		)
		(fp_rect
			(start -0.95 0.675)
			(end 0.95 -0.675)
			(stroke
				(width 0.15)
				(type solid)
			)
			(fill no)
			(layer "B.Fab")
		)
		(pad "1" smd roundrect
			(at -1.1 0 90)
			(size 1.2 1.3)
			(layers "B.Cu" "B.Mask" "B.Paste")
			(roundrect_rratio 0.25)
			(net 2 "GND")
			(pintype "passive")
		)
		(pad "2" smd roundrect
			(at 1.1 0 90)
			(size 1.2 1.3)
			(layers "B.Cu" "B.Mask" "B.Paste")
			(roundrect_rratio 0.25)
			(net 5 "+12V")
			(pintype "passive")
		)
	)
)
